(kicad_pcb
	(version 20260206)
	(generator "pcbnew")
	(generator_version "10.0")
	(general
		(thickness 1.6)
		(legacy_teardrops no)
	)
	(paper "A4")
	(title_block
		(title "v2-tray-backplane — ms_tbp_v2.brd")
		(comment 1 "Open CloudServer (Microsoft) / footprints 148-153 of 164")
	)
	(layers
		(0 "F.Cu" signal "TOP")
		(4 "In1.Cu" signal "LYR2")
		(6 "In2.Cu" signal "LYR3")
		(8 "In3.Cu" signal "LYR4")
		(10 "In4.Cu" signal "LYR5")
		(12 "In5.Cu" signal "LYR6")
		(14 "In6.Cu" signal "LYR7")
		(2 "B.Cu" signal "BOTTOM")
		(9 "F.Adhes" user "F.Adhesive")
		(11 "B.Adhes" user "B.Adhesive")
		(13 "F.Paste" user "Package Geometry/Pastemask Top")
		(15 "B.Paste" user "Package Geometry/Pastemask Bottom")
		(5 "F.SilkS" user "Ref Des/Silkscreen Top")
		(7 "B.SilkS" user "Ref Des/Silkscreen Bottom")
		(1 "F.Mask" user "Board Geometry/Soldermask Top")
		(3 "B.Mask" user "Board Geometry/Soldermask Bottom")
		(17 "Dwgs.User" user "User.Drawings")
		(19 "Cmts.User" user "User.Comments")
		(21 "Eco1.User" user "User.Eco1")
		(23 "Eco2.User" user "User.Eco2")
		(25 "Edge.Cuts" user "Board Geometry/Outline")
		(27 "Margin" user)
		(31 "F.CrtYd" user "Package Geometry/Place Bound Top")
		(29 "B.CrtYd" user "Package Geometry/Place Bound Bottom")
		(35 "F.Fab" user "Ref Des/Assembly Top")
		(33 "B.Fab" user "Ref Des/Assembly Bottom")
	)
	(footprint ""
		(layer "F.Cu")
		(at -61.750001 32.059999 180)
		(property "Reference" "J18"
			(at -7.048561 -7.203321 0)
			(unlocked yes)
			(layer "F.SilkS")
			(effects
				(font
					(size 0.762 0.5334)
					(thickness 0.1016)
				)
			)
		)
		(property "Value" ""
			(at 0 0 180)
			(layer "F.Fab")
			(effects
				(font
					(size 1.27 1.27)
				)
			)
		)
		(duplicate_pad_numbers_are_jumpers no)
		(fp_line
			(start 8.099999 42.399999)
			(end 8.099999 27.999999)
			(stroke
				(width 0.127)
				(type default)
			)
			(layer "F.SilkS")
		)
		(fp_line
			(start 8.099999 23.099999)
			(end 8.099999 17.999999)
			(stroke
				(width 0.127)
				(type default)
			)
			(layer "F.SilkS")
		)
		(fp_line
			(start 8.099999 13.8)
			(end 8.099999 7.899999)
			(stroke
				(width 0.127)
				(type default)
			)
			(layer "F.SilkS")
		)
		(fp_line
			(start 8.099999 4.199999)
			(end 8.099999 -2.400001)
			(stroke
				(width 0.127)
				(type default)
			)
			(layer "F.SilkS")
		)
		(fp_line
			(start 8.099999 -5.699999)
			(end 8.099999 -6.3)
			(stroke
				(width 0.127)
				(type default)
			)
			(layer "F.SilkS")
		)
		(fp_line
			(start 8.099999 -6.3)
			(end 6.000001 -6.3)
			(stroke
				(width 0.127)
				(type default)
			)
			(layer "F.SilkS")
		)
		(fp_line
			(start -6.000001 -6.3)
			(end -8.099999 -6.3)
			(stroke
				(width 0.127)
				(type default)
			)
			(layer "F.SilkS")
		)
		(fp_line
			(start -8.099999 42.399999)
			(end 8.099999 42.399999)
			(stroke
				(width 0.127)
				(type default)
			)
			(layer "F.SilkS")
		)
		(fp_line
			(start -8.099999 32.8)
			(end -8.099999 42.399999)
			(stroke
				(width 0.127)
				(type default)
			)
			(layer "F.SilkS")
		)
		(fp_line
			(start -8.099999 22.999999)
			(end -8.099999 28.9)
			(stroke
				(width 0.127)
				(type default)
			)
			(layer "F.SilkS")
		)
		(fp_line
			(start -8.099999 12.999999)
			(end -8.099999 18.600001)
			(stroke
				(width 0.127)
				(type default)
			)
			(layer "F.SilkS")
		)
		(fp_line
			(start -8.099999 2.5)
			(end -8.099999 9.099999)
			(stroke
				(width 0.127)
				(type default)
			)
			(layer "F.SilkS")
		)
		(fp_line
			(start -8.099999 -6.3)
			(end -8.099999 -0.700002)
			(stroke
				(width 0.127)
				(type default)
			)
			(layer "F.SilkS")
		)
		(fp_poly
			(pts
				(arc
					(start 5.2054 34.950301)
					(mid 3.459364 36.043267)
					(end 1.434201 36.42)
				)
				(arc
					(start -7.124799 36.42)
					(mid -11.028153 34.803295)
					(end -12.644999 30.899999)
				)
				(xy -12.6495 30.899999) (xy -12.6495 0.9)
				(arc
					(start -12.644999 0.9)
					(mid -12.630104 0.494905)
					(end -12.585499 0.091998)
				)
				(arc
					(start -12.368601 -1.986699)
					(mid -12.153073 -3.137304)
					(end -11.6883 -4.211701)
				)
				(arc
					(start -9.540999 -8.473202)
					(mid -7.601127 -10.649546)
					(end -4.800001 -11.457801)
				)
				(arc
					(start 4.800001 -11.457801)
					(mid 6.526796 -11.166136)
					(end 8.062001 -10.3235)
				)
				(arc
					(start 10.390299 -8.5507)
					(mid 12.049188 -6.594625)
					(end 12.644999 -4.1)
				)
				(xy 12.6495 -4.1) (xy 12.6495 25.899999)
				(arc
					(start 12.644999 25.899999)
					(mid 12.153739 28.176398)
					(end 10.7674 30.0476)
				)
			)
			(stroke
				(width 0)
				(type default)
			)
			(fill no)
			(layer "B.CrtYd")
		)
		(fp_poly
			(pts
				(xy 9.1 43.399999) (xy -9.1 43.399999) (xy -9.1 -7.9) (xy 9.1 -7.9)
			)
			(stroke
				(width 0)
				(type default)
			)
			(fill no)
			(layer "F.CrtYd")
		)
		(fp_line
			(start 8.099999 42.399999)
			(end -8.099999 42.399999)
			(stroke
				(width 0.1)
				(type default)
			)
			(layer "F.Fab")
		)
		(fp_line
			(start 8.099999 -6.32)
			(end 8.099999 42.399999)
			(stroke
				(width 0.1)
				(type default)
			)
			(layer "F.Fab")
		)
		(fp_line
			(start -8.099999 42.399999)
			(end -8.099999 -6.32)
			(stroke
				(width 0.1)
				(type default)
			)
			(layer "F.Fab")
		)
		(fp_line
			(start -8.099999 -6.32)
			(end 8.099999 -6.32)
			(stroke
				(width 0.1)
				(type default)
			)
			(layer "F.Fab")
		)
		(pad "1" thru_hole circle
			(at 0 -6.2 180)
			(size 1.4732 1.4732)
			(drill 0.9652)
			(layers "*.Cu" "*.Mask")
			(remove_unused_layers no)
			(net "GND")
		)
		(pad "2" thru_hole circle
			(at -4.800001 -6.2 180)
			(size 1.4732 1.4732)
			(drill 0.9652)
			(layers "*.Cu" "*.Mask")
			(remove_unused_layers no)
			(net "GND")
		)
		(pad "3" thru_hole circle
			(at 4.800001 -6.2 180)
			(size 1.4732 1.4732)
			(drill 0.9652)
			(layers "*.Cu" "*.Mask")
			(remove_unused_layers no)
			(net "GND")
		)
		(pad "4" thru_hole rect
			(at 7.125 -4.099999 180)
			(size 2.0066 2.0066)
			(drill 1.0414)
			(layers "*.Cu" "*.Mask")
			(remove_unused_layers no)
			(net "GND")
			(padstack
				(mode front_inner_back)
				(layer "Inner"
					(shape circle)
					(size 2.0066 2.0066)
				)
				(layer "B.Cu"
					(shape rect)
					(size 2.0066 2.0066)
				)
			)
		)
		(pad "5" thru_hole circle
			(at -7.125 -1.599999 180)
			(size 1.4732 1.4732)
			(drill 0.9652)
			(layers "*.Cu" "*.Mask")
			(remove_unused_layers no)
			(net "GND")
		)
		(pad "6" thru_hole circle
			(at 7.125 -1.599999 180)
			(size 1.4732 1.4732)
			(drill 0.9652)
			(layers "*.Cu" "*.Mask")
			(remove_unused_layers no)
			(net "GND")
		)
		(pad "7" thru_hole rect
			(at -7.125 0.900001 180)
			(size 2.0066 2.0066)
			(drill 0.8382)
			(layers "*.Cu" "*.Mask")
			(remove_unused_layers no)
			(net "GND")
			(padstack
				(mode front_inner_back)
				(layer "Inner"
					(shape circle)
					(size 2.0066 2.0066)
				)
				(layer "B.Cu"
					(shape rect)
					(size 2.0066 2.0066)
				)
			)
		)
		(pad "8" thru_hole circle
			(at -7.125 3.400001 180)
			(size 1.4732 1.4732)
			(drill 0.9652)
			(layers "*.Cu" "*.Mask")
			(remove_unused_layers no)
			(net "GND")
		)
		(pad "9" thru_hole circle
			(at 7.125 3.400001 180)
			(size 1.4732 1.4732)
			(drill 0.9652)
			(layers "*.Cu" "*.Mask")
			(remove_unused_layers no)
			(net "GND")
		)
		(pad "10" thru_hole rect
			(at 7.125 5.900001 180)
			(size 2.0066 2.0066)
			(drill 1.0414)
			(layers "*.Cu" "*.Mask")
			(remove_unused_layers no)
			(net "GND")
			(padstack
				(mode front_inner_back)
				(layer "Inner"
					(shape circle)
					(size 2.0066 2.0066)
				)
				(layer "B.Cu"
					(shape rect)
					(size 2.0066 2.0066)
				)
			)
		)
		(pad "11" thru_hole circle
			(at -7.125 8.099999 180)
			(size 1.4732 1.4732)
			(drill 0.9652)
			(layers "*.Cu" "*.Mask")
			(remove_unused_layers no)
			(net "GND")
		)
		(pad "12" thru_hole circle
			(at 7.125 8.099999 180)
			(size 1.4732 1.4732)
			(drill 0.9652)
			(layers "*.Cu" "*.Mask")
			(remove_unused_layers no)
			(net "GND")
		)
		(pad "13" thru_hole rect
			(at -7.125 10.900001 180)
			(size 2.0066 2.0066)
			(drill 1.0414)
			(layers "*.Cu" "*.Mask")
			(remove_unused_layers no)
			(net "GND")
			(padstack
				(mode front_inner_back)
				(layer "Inner"
					(shape circle)
					(size 2.0066 2.0066)
				)
				(layer "B.Cu"
					(shape rect)
					(size 2.0066 2.0066)
				)
			)
		)
		(pad "14" thru_hole rect
			(at -1.445001 10.900001 180)
			(size 2.0066 2.0066)
			(drill 1.0414)
			(layers "*.Cu" "*.Mask")
			(remove_unused_layers no)
			(net "GND")
			(padstack
				(mode front_inner_back)
				(layer "Inner"
					(shape circle)
					(size 2.0066 2.0066)
				)
				(layer "B.Cu"
					(shape rect)
					(size 2.0066 2.0066)
				)
			)
		)
		(pad "15" thru_hole rect
			(at 3.955001 10.900001 180)
			(size 2.0066 2.0066)
			(drill 1.0414)
			(layers "*.Cu" "*.Mask")
			(remove_unused_layers no)
			(net "GND")
			(padstack
				(mode front_inner_back)
				(layer "Inner"
					(shape circle)
					(size 2.0066 2.0066)
				)
				(layer "B.Cu"
					(shape rect)
					(size 2.0066 2.0066)
				)
			)
		)
		(pad "16" thru_hole rect
			(at 7.125 15.900001 180)
			(size 2.0066 2.0066)
			(drill 1.0414)
			(layers "*.Cu" "*.Mask")
			(remove_unused_layers no)
			(net "GND")
			(padstack
				(mode front_inner_back)
				(layer "Inner"
					(shape circle)
					(size 2.0066 2.0066)
				)
				(layer "B.Cu"
					(shape rect)
					(size 2.0066 2.0066)
				)
			)
		)
		(pad "17" thru_hole rect
			(at -7.125 20.899999 180)
			(size 2.0066 2.0066)
			(drill 1.0414)
			(layers "*.Cu" "*.Mask")
			(remove_unused_layers no)
			(net "GND")
			(padstack
				(mode front_inner_back)
				(layer "Inner"
					(shape circle)
					(size 2.0066 2.0066)
				)
				(layer "B.Cu"
					(shape rect)
					(size 2.0066 2.0066)
				)
			)
		)
		(pad "18" thru_hole rect
			(at 7.125 25.899999 180)
			(size 2.0066 2.0066)
			(drill 1.0414)
			(layers "*.Cu" "*.Mask")
			(remove_unused_layers no)
			(net "GND")
			(padstack
				(mode front_inner_back)
				(layer "Inner"
					(shape circle)
					(size 2.0066 2.0066)
				)
				(layer "B.Cu"
					(shape rect)
					(size 2.0066 2.0066)
				)
			)
		)
		(pad "19" thru_hole rect
			(at -7.125 30.899999 180)
			(size 2.0066 2.0066)
			(drill 1.0414)
			(layers "*.Cu" "*.Mask")
			(remove_unused_layers no)
			(net "GND")
			(padstack
				(mode front_inner_back)
				(layer "Inner"
					(shape circle)
					(size 2.0066 2.0066)
				)
				(layer "B.Cu"
					(shape rect)
					(size 2.0066 2.0066)
				)
			)
		)
		(pad "20" thru_hole rect
			(at 1.455001 30.899999 180)
			(size 2.0066 2.0066)
			(drill 1.0414)
			(layers "*.Cu" "*.Mask")
			(remove_unused_layers no)
			(net "GND")
			(padstack
				(mode front_inner_back)
				(layer "Inner"
					(shape circle)
					(size 2.0066 2.0066)
				)
				(layer "B.Cu"
					(shape rect)
					(size 2.0066 2.0066)
				)
			)
		)
	)
	(footprint ""
		(layer "F.Cu")
		(at -110.8456 11.8364)
		(property "Reference" "R65"
			(at 2.6416 0.0127 0)
			(unlocked yes)
			(layer "F.SilkS")
			(effects
				(font
					(size 0.762 0.5334)
					(thickness 0.1016)
				)
			)
		)
		(property "Value" ""
			(at 0 0 0)
			(layer "F.Fab")
			(effects
				(font
					(size 1.27 1.27)
				)
			)
		)
		(duplicate_pad_numbers_are_jumpers no)
		(fp_line
			(start 0 -0.381)
			(end 0 0.381)
			(stroke
				(width 0.127)
				(type default)
			)
			(layer "F.SilkS")
		)
		(fp_poly
			(pts
				(xy 1.255601 0.6564) (xy -1.255601 0.6564) (xy -1.255601 -0.656399) (xy 1.255601 -0.656399)
			)
			(stroke
				(width 0)
				(type default)
			)
			(fill no)
			(layer "F.CrtYd")
		)
		(fp_line
			(start -0.800001 -0.399999)
			(end -0.800001 0.399999)
			(stroke
				(width 0.1)
				(type default)
			)
			(layer "F.Fab")
		)
		(fp_line
			(start -0.800001 0.399999)
			(end 0.800001 0.399999)
			(stroke
				(width 0.1)
				(type default)
			)
			(layer "F.Fab")
		)
		(fp_line
			(start 0.800001 -0.399999)
			(end -0.800001 -0.399999)
			(stroke
				(width 0.1)
				(type default)
			)
			(layer "F.Fab")
		)
		(fp_line
			(start 0.800001 0.399999)
			(end 0.800001 -0.399999)
			(stroke
				(width 0.1)
				(type default)
			)
			(layer "F.Fab")
		)
		(pad "1" smd rect
			(at -0.650001 0)
			(size 0.7112 0.8128)
			(layers "F.Cu" "F.Mask" "F.Paste")
			(net "ETH40G_B2_LPMODE")
		)
		(pad "2" smd rect
			(at 0.650001 0 180)
			(size 0.7112 0.8128)
			(layers "F.Cu" "F.Mask" "F.Paste")
			(net "GND")
		)
	)
	(footprint ""
		(layer "F.Cu")
		(at -110.8456 17.4244 180)
		(property "Reference" "R61"
			(at -2.5146 -0.0127 0)
			(unlocked yes)
			(layer "F.SilkS")
			(effects
				(font
					(size 0.762 0.5334)
					(thickness 0.1016)
				)
			)
		)
		(property "Value" ""
			(at 0 0 180)
			(layer "F.Fab")
			(effects
				(font
					(size 1.27 1.27)
				)
			)
		)
		(duplicate_pad_numbers_are_jumpers no)
		(fp_line
			(start 0 -0.381)
			(end 0 0.381)
			(stroke
				(width 0.127)
				(type default)
			)
			(layer "F.SilkS")
		)
		(fp_poly
			(pts
				(xy 1.255601 0.656399) (xy -1.255601 0.656399) (xy -1.255601 -0.6564) (xy 1.255601 -0.6564)
			)
			(stroke
				(width 0)
				(type default)
			)
			(fill no)
			(layer "F.CrtYd")
		)
		(fp_line
			(start 0.800001 0.399999)
			(end 0.800001 -0.399999)
			(stroke
				(width 0.1)
				(type default)
			)
			(layer "F.Fab")
		)
		(fp_line
			(start 0.800001 -0.399999)
			(end -0.800001 -0.399999)
			(stroke
				(width 0.1)
				(type default)
			)
			(layer "F.Fab")
		)
		(fp_line
			(start -0.800001 0.399999)
			(end 0.800001 0.399999)
			(stroke
				(width 0.1)
				(type default)
			)
			(layer "F.Fab")
		)
		(fp_line
			(start -0.800001 -0.399999)
			(end -0.800001 0.399999)
			(stroke
				(width 0.1)
				(type default)
			)
			(layer "F.Fab")
		)
		(pad "1" smd rect
			(at -0.650001 0 180)
			(size 0.7112 0.8128)
			(layers "F.Cu" "F.Mask" "F.Paste")
			(net "SKU_B2_ID2")
		)
		(pad "2" smd rect
			(at 0.650001 0)
			(size 0.7112 0.8128)
			(layers "F.Cu" "F.Mask" "F.Paste")
			(net "ETH40G_B2_RESET_N")
		)
	)
	(footprint ""
		(layer "F.Cu")
		(at -75.3618 10.9982 180)
		(property "Reference" "R56"
			(at -3.048 -0.0381 0)
			(unlocked yes)
			(layer "F.SilkS")
			(effects
				(font
					(size 0.762 0.5334)
					(thickness 0.1016)
				)
			)
		)
		(property "Value" ""
			(at 0 0 180)
			(layer "F.Fab")
			(effects
				(font
					(size 1.27 1.27)
				)
			)
		)
		(duplicate_pad_numbers_are_jumpers no)
		(fp_line
			(start 0 -0.381)
			(end 0 0.381)
			(stroke
				(width 0.127)
				(type default)
			)
			(layer "F.SilkS")
		)
		(fp_poly
			(pts
				(xy 1.255601 0.656399) (xy -1.255601 0.656399) (xy -1.255601 -0.6564) (xy 1.255601 -0.6564)
			)
			(stroke
				(width 0)
				(type default)
			)
			(fill no)
			(layer "F.CrtYd")
		)
		(fp_line
			(start 0.800001 0.399999)
			(end 0.800001 -0.399999)
			(stroke
				(width 0.1)
				(type default)
			)
			(layer "F.Fab")
		)
		(fp_line
			(start 0.800001 -0.399999)
			(end -0.800001 -0.399999)
			(stroke
				(width 0.1)
				(type default)
			)
			(layer "F.Fab")
		)
		(fp_line
			(start -0.800001 0.399999)
			(end 0.800001 0.399999)
			(stroke
				(width 0.1)
				(type default)
			)
			(layer "F.Fab")
		)
		(fp_line
			(start -0.800001 -0.399999)
			(end -0.800001 0.399999)
			(stroke
				(width 0.1)
				(type default)
			)
			(layer "F.Fab")
		)
		(pad "1" smd rect
			(at -0.650001 0 180)
			(size 0.7112 0.8128)
			(layers "F.Cu" "F.Mask" "F.Paste")
			(net "P3V3_B2_QSFP")
		)
		(pad "2" smd rect
			(at 0.650001 0)
			(size 0.7112 0.8128)
			(layers "F.Cu" "F.Mask" "F.Paste")
			(net "ETH10G_B2_SCL")
		)
	)
	(footprint ""
		(layer "F.Cu")
		(at -266.192 2.54 180)
		(property "Reference" "R73"
			(at -3.175 -0.1651 0)
			(unlocked yes)
			(layer "F.SilkS")
			(effects
				(font
					(size 0.762 0.5334)
					(thickness 0.1016)
				)
			)
		)
		(property "Value" ""
			(at 0 0 180)
			(layer "F.Fab")
			(effects
				(font
					(size 1.27 1.27)
				)
			)
		)
		(duplicate_pad_numbers_are_jumpers no)
		(fp_line
			(start 0 -0.381)
			(end 0 0.381)
			(stroke
				(width 0.127)
				(type default)
			)
			(layer "F.SilkS")
		)
		(fp_poly
			(pts
				(xy 1.255601 0.656399) (xy -1.255601 0.656399) (xy -1.255601 -0.6564) (xy 1.255601 -0.6564)
			)
			(stroke
				(width 0)
				(type default)
			)
			(fill no)
			(layer "F.CrtYd")
		)
		(fp_line
			(start 0.800001 0.399999)
			(end 0.800001 -0.399999)
			(stroke
				(width 0.1)
				(type default)
			)
			(layer "F.Fab")
		)
		(fp_line
			(start 0.800001 -0.399999)
			(end -0.800001 -0.399999)
			(stroke
				(width 0.1)
				(type default)
			)
			(layer "F.Fab")
		)
		(fp_line
			(start -0.800001 0.399999)
			(end 0.800001 0.399999)
			(stroke
				(width 0.1)
				(type default)
			)
			(layer "F.Fab")
		)
		(fp_line
			(start -0.800001 -0.399999)
			(end -0.800001 0.399999)
			(stroke
				(width 0.1)
				(type default)
			)
			(layer "F.Fab")
		)
		(pad "1" smd rect
			(at -0.650001 0 180)
			(size 0.7112 0.8128)
			(layers "F.Cu" "F.Mask" "F.Paste")
			(net "P3V3_B1_QSFP")
		)
		(pad "2" smd rect
			(at 0.650001 0)
			(size 0.7112 0.8128)
			(layers "F.Cu" "F.Mask" "F.Paste")
			(net "P3V3_40G_B1_VCC_RX")
		)
	)
	(footprint ""
		(layer "F.Cu")
		(at -267.774001 11.646002 90)
		(property "Reference" "FB10"
			(at 0.558902 -3.624999 0)
			(unlocked yes)
			(layer "F.SilkS")
			(effects
				(font
					(size 0.762 0.5334)
					(thickness 0.1016)
				)
				(justify left)
			)
		)
		(property "Value" ""
			(at 0 0 90)
			(layer "F.Fab")
			(effects
				(font
					(size 1.27 1.27)
				)
			)
		)
		(duplicate_pad_numbers_are_jumpers no)
		(fp_poly
			(pts
				(xy -1.016 0.508) (xy -1.016 -0.508) (xy 1.016 -0.508) (xy 1.016 0.508)
			)
			(stroke
				(width 0)
				(type default)
			)
			(fill no)
			(layer "F.CrtYd")
		)
		(fp_line
			(start 0.508 -0.254)
			(end 0.508 0.254)
			(stroke
				(width 0.1)
				(type default)
			)
			(layer "F.Fab")
		)
		(fp_line
			(start -0.508 -0.254)
			(end 0.508 -0.254)
			(stroke
				(width 0.1)
				(type default)
			)
			(layer "F.Fab")
		)
		(fp_line
			(start 0.508 0.254)
			(end -0.508 0.254)
			(stroke
				(width 0.1)
				(type default)
			)
			(layer "F.Fab")
		)
		(fp_line
			(start -0.508 0.254)
			(end -0.508 -0.254)
			(stroke
				(width 0.1)
				(type default)
			)
			(layer "F.Fab")
		)
		(pad "1" smd rect
			(at -0.4572 0 180)
			(size 0.508 0.5842)
			(layers "F.Cu" "F.Mask" "F.Paste")
			(net "P3V3_40G_B1_VCC1")
		)
		(pad "2" smd rect
			(at 0.4572 0 180)
			(size 0.508 0.5842)
			(layers "F.Cu" "F.Mask" "F.Paste")
			(net "UNNAMED_16_FERRITE_I46_B")
		)
	)
)
